(kicad_pcb
	(version 20241229)
	(generator "pcbnew")
	(generator_version "9.0")
	(general
		(thickness 1.61)
		(legacy_teardrops no)
	)
	(paper "A3")
	(title_block
		(title "RDIMM DDR5 Tester")
		(date "2026-05-21")
		(rev "2.2.0")
		(company "Antmicro")
		(comment 9 "footprints 664-668 of 796")
	)
	(layers
		(0 "F.Cu" signal)
		(4 "In1.Cu" power)
		(6 "In2.Cu" mixed)
		(8 "In3.Cu" power)
		(10 "In4.Cu" mixed)
		(12 "In5.Cu" power)
		(14 "In6.Cu" mixed)
		(16 "In7.Cu" power)
		(18 "In8.Cu" power)
		(20 "In9.Cu" mixed)
		(22 "In10.Cu" power)
		(2 "B.Cu" signal)
		(9 "F.Adhes" user "F.Adhesive")
		(11 "B.Adhes" user "B.Adhesive")
		(13 "F.Paste" user)
		(15 "B.Paste" user)
		(5 "F.SilkS" user "F.Silkscreen")
		(7 "B.SilkS" user "B.Silkscreen")
		(1 "F.Mask" user)
		(3 "B.Mask" user)
		(17 "Dwgs.User" user "User.Drawings")
		(19 "Cmts.User" user "User.Comments")
		(21 "Eco1.User" user "User.Eco1")
		(23 "Eco2.User" user "User.Eco2")
		(25 "Edge.Cuts" user)
		(27 "Margin" user)
		(31 "F.CrtYd" user "F.Courtyard")
		(29 "B.CrtYd" user "B.Courtyard")
		(35 "F.Fab" user)
		(33 "B.Fab" user)
	)
	(footprint "antmicro-footprints:R_0402_1005Metric"
		(layer "B.Cu")
		(at 253.039499 141.3)
		(descr "Resistor SMD 0402")
		(tags "resistor SMD 0402")
		(property "Reference" "R184"
			(at -4.089499 0.4 0)
			(layer "B.SilkS")
			(effects
				(font
					(size 0.7 0.7)
					(thickness 0.15)
				)
				(justify right bottom mirror)
			)
		)
		(property "Value" "R_47k_0402"
			(at -1.011843 -1.772047 0)
			(layer "B.Fab")
			(effects
				(font
					(size 0.7 0.7)
					(thickness 0.15)
				)
				(justify right bottom mirror)
			)
		)
		(property "Datasheet" "https://www.bourns.com/docs/product-datasheets/cr.pdf"
			(at 0 0 0)
			(layer "F.Fab")
			(hide yes)
			(effects
				(font
					(size 1.27 1.27)
					(thickness 0.15)
				)
			)
		)
		(property "Manufacturer" "Bourns"
			(at 0 0 0)
			(unlocked yes)
			(layer "B.Fab")
			(hide yes)
			(effects
				(font
					(size 1 1)
					(thickness 0.15)
				)
				(justify mirror)
			)
		)
		(property "MPN" "CR0402-FX-4702GLF"
			(at 0 0 0)
			(unlocked yes)
			(layer "B.Fab")
			(hide yes)
			(effects
				(font
					(size 1 1)
					(thickness 0.15)
				)
				(justify mirror)
			)
		)
		(property "Val" "47k"
			(at 0 0 0)
			(unlocked yes)
			(layer "B.Fab")
			(hide yes)
			(effects
				(font
					(size 1 1)
					(thickness 0.15)
				)
				(justify mirror)
			)
		)
		(property "License" "Apache-2.0"
			(at 0 0 0)
			(unlocked yes)
			(layer "B.Fab")
			(hide yes)
			(effects
				(font
					(size 1 1)
					(thickness 0.15)
				)
				(justify mirror)
			)
		)
		(property "Author" "Antmicro"
			(at 0 0 0)
			(unlocked yes)
			(layer "B.Fab")
			(hide yes)
			(effects
				(font
					(size 1 1)
					(thickness 0.15)
				)
				(justify mirror)
			)
		)
		(property "Tolerance" "1%"
			(at 0 0 0)
			(unlocked yes)
			(layer "B.Fab")
			(hide yes)
			(effects
				(font
					(size 1 1)
					(thickness 0.15)
				)
				(justify mirror)
			)
		)
		(sheetname "/Supply/")
		(sheetfile "supply.kicad_sch")
		(attr smd)
		(fp_rect
			(start -0.925 0.47)
			(end 0.925 -0.47)
			(stroke
				(width 0.05)
				(type default)
			)
			(fill no)
			(layer "B.CrtYd")
		)
		(fp_rect
			(start -0.5 0.25)
			(end 0.5 -0.25)
			(stroke
				(width 0.15)
				(type solid)
			)
			(fill no)
			(layer "B.Fab")
		)
		(fp_text user "License: Apache-2.0"
			(at -0.95 -5.169 180)
			(layer "B.Fab")
			(effects
				(font
					(size 0.7 0.7)
					(thickness 0.15)
				)
				(justify left bottom mirror)
			)
		)
		(fp_text user "${REFERENCE}"
			(at -0.95 -3.168 180)
			(layer "B.Fab")
			(effects
				(font
					(size 0.7 0.7)
					(thickness 0.15)
				)
				(justify left bottom mirror)
			)
		)
		(fp_text user "Author: Antmicro"
			(at -0.95 -4.169 180)
			(layer "B.Fab")
			(effects
				(font
					(size 0.7 0.7)
					(thickness 0.15)
				)
				(justify left bottom mirror)
			)
		)
		(pad "1" smd roundrect
			(at -0.48 0)
			(size 0.59 0.64)
			(layers "B.Cu" "B.Mask" "B.Paste")
			(roundrect_rratio 0.25)
			(net 168 "/Supply/EN1")
			(pintype "passive")
		)
		(pad "2" smd roundrect
			(at 0.48 0)
			(size 0.59 0.64)
			(layers "B.Cu" "B.Mask" "B.Paste")
			(roundrect_rratio 0.25)
			(net 38 "+3V3_AON")
			(pintype "passive")
		)
	)
	(footprint "antmicro-footprints:R_0402_1005Metric"
		(layer "B.Cu")
		(at 238.777999 141.151 180)
		(descr "Resistor SMD 0402")
		(tags "resistor SMD 0402")
		(property "Reference" "R140"
			(at -4.365499 -0.4225 0)
			(layer "B.SilkS")
			(effects
				(font
					(size 0.7 0.7)
					(thickness 0.15)
				)
				(justify left bottom mirror)
			)
		)
		(property "Value" "R_47k_0402"
			(at -1.011843 -1.772047 0)
			(layer "B.Fab")
			(effects
				(font
					(size 0.7 0.7)
					(thickness 0.15)
				)
				(justify left bottom mirror)
			)
		)
		(property "Datasheet" "https://www.bourns.com/docs/product-datasheets/cr.pdf"
			(at 0 0 180)
			(layer "F.Fab")
			(hide yes)
			(effects
				(font
					(size 1.27 1.27)
					(thickness 0.15)
				)
			)
		)
		(property "Manufacturer" "Bourns"
			(at 0 0 180)
			(unlocked yes)
			(layer "B.Fab")
			(hide yes)
			(effects
				(font
					(size 1 1)
					(thickness 0.15)
				)
				(justify mirror)
			)
		)
		(property "MPN" "CR0402-FX-4702GLF"
			(at 0 0 180)
			(unlocked yes)
			(layer "B.Fab")
			(hide yes)
			(effects
				(font
					(size 1 1)
					(thickness 0.15)
				)
				(justify mirror)
			)
		)
		(property "Val" "47k"
			(at 0 0 180)
			(unlocked yes)
			(layer "B.Fab")
			(hide yes)
			(effects
				(font
					(size 1 1)
					(thickness 0.15)
				)
				(justify mirror)
			)
		)
		(property "License" "Apache-2.0"
			(at 0 0 180)
			(unlocked yes)
			(layer "B.Fab")
			(hide yes)
			(effects
				(font
					(size 1 1)
					(thickness 0.15)
				)
				(justify mirror)
			)
		)
		(property "Author" "Antmicro"
			(at 0 0 180)
			(unlocked yes)
			(layer "B.Fab")
			(hide yes)
			(effects
				(font
					(size 1 1)
					(thickness 0.15)
				)
				(justify mirror)
			)
		)
		(property "Tolerance" "1%"
			(at 0 0 180)
			(unlocked yes)
			(layer "B.Fab")
			(hide yes)
			(effects
				(font
					(size 1 1)
					(thickness 0.15)
				)
				(justify mirror)
			)
		)
		(sheetname "/Supply/")
		(sheetfile "supply.kicad_sch")
		(attr smd)
		(fp_rect
			(start -0.925 0.47)
			(end 0.925 -0.47)
			(stroke
				(width 0.05)
				(type default)
			)
			(fill no)
			(layer "B.CrtYd")
		)
		(fp_rect
			(start -0.5 0.25)
			(end 0.5 -0.25)
			(stroke
				(width 0.15)
				(type solid)
			)
			(fill no)
			(layer "B.Fab")
		)
		(fp_text user "License: Apache-2.0"
			(at -0.95 -5.169 0)
			(layer "B.Fab")
			(effects
				(font
					(size 0.7 0.7)
					(thickness 0.15)
				)
				(justify left bottom mirror)
			)
		)
		(fp_text user "${REFERENCE}"
			(at -0.95 -3.168 0)
			(layer "B.Fab")
			(effects
				(font
					(size 0.7 0.7)
					(thickness 0.15)
				)
				(justify left bottom mirror)
			)
		)
		(fp_text user "Author: Antmicro"
			(at -0.95 -4.169 0)
			(layer "B.Fab")
			(effects
				(font
					(size 0.7 0.7)
					(thickness 0.15)
				)
				(justify left bottom mirror)
			)
		)
		(pad "1" smd roundrect
			(at -0.48 0 180)
			(size 0.59 0.64)
			(layers "B.Cu" "B.Mask" "B.Paste")
			(roundrect_rratio 0.25)
			(net 405 "IN2")
			(pintype "passive")
		)
		(pad "2" smd roundrect
			(at 0.48 0 180)
			(size 0.59 0.64)
			(layers "B.Cu" "B.Mask" "B.Paste")
			(roundrect_rratio 0.25)
			(net 38 "+3V3_AON")
			(pintype "passive")
		)
	)
	(footprint "antmicro-footprints:NetTie-2_SMD_Pad0.127mm"
		(layer "B.Cu")
		(at 205.823 150.8 180)
		(descr "Net tie, 2 pin, 0.127mm  SMD pads")
		(tags "net tie")
		(property "Reference" "TP3"
			(at -0.128 1.345 0)
			(layer "B.SilkS")
			(hide yes)
			(effects
				(font
					(size 0.7 0.7)
					(thickness 0.15)
				)
				(justify left bottom mirror)
			)
		)
		(property "Value" "Net-Tie_P0.127mm"
			(at 0 -1.199 0)
			(layer "B.Fab")
			(effects
				(font
					(size 0.7 0.7)
					(thickness 0.15)
				)
				(justify left bottom mirror)
			)
		)
		(property "MPN" ""
			(at 0 0 180)
			(unlocked yes)
			(layer "B.Fab")
			(hide yes)
			(effects
				(font
					(size 1 1)
					(thickness 0.15)
				)
				(justify mirror)
			)
		)
		(property "Manufacturer" ""
			(at 0 0 180)
			(unlocked yes)
			(layer "B.Fab")
			(hide yes)
			(effects
				(font
					(size 1 1)
					(thickness 0.15)
				)
				(justify mirror)
			)
		)
		(property "Author" "Antmicro"
			(at 0 0 180)
			(unlocked yes)
			(layer "B.Fab")
			(hide yes)
			(effects
				(font
					(size 1 1)
					(thickness 0.15)
				)
				(justify mirror)
			)
		)
		(property "License" "Apache-2.0"
			(at 0 0 180)
			(unlocked yes)
			(layer "B.Fab")
			(hide yes)
			(effects
				(font
					(size 1 1)
					(thickness 0.15)
				)
				(justify mirror)
			)
		)
		(property ki_fp_filters "Net*Tie*")
		(sheetname "/FPGA Config/")
		(sheetfile "fpga-config.kicad_sch")
		(attr through_hole exclude_from_pos_files exclude_from_bom)
		(net_tie_pad_groups "1, 2")
		(fp_poly
			(pts
				(xy -0.0635 0.0635) (xy 0.0625 0.0635) (xy 0.0625 -0.0635) (xy -0.0635 -0.0635)
			)
			(stroke
				(width 0)
				(type solid)
			)
			(fill yes)
			(layer "B.Cu")
		)
		(fp_poly
			(pts
				(xy 0.2 0.16) (xy 0.29 0.07) (xy 0.29 -0.07) (xy 0.2 -0.16) (xy -0.2 -0.16) (xy -0.29 -0.07) (xy -0.29 0.06)
				(xy -0.19 0.16)
			)
			(stroke
				(width 0.05)
				(type solid)
			)
			(fill no)
			(layer "B.CrtYd")
		)
		(fp_text user "Author: Antmicro"
			(at -0.128 -4.4 0)
			(layer "B.Fab")
			(effects
				(font
					(size 0.7 0.7)
					(thickness 0.15)
				)
				(justify left bottom mirror)
			)
		)
		(fp_text user "License: Apache-2.0"
			(at -0.128 -5.6 0)
			(layer "B.Fab")
			(effects
				(font
					(size 0.7 0.7)
					(thickness 0.15)
				)
				(justify left bottom mirror)
			)
		)
		(fp_text user "${REFERENCE}"
			(at -0.128 -3.2 0)
			(layer "B.Fab")
			(effects
				(font
					(size 0.7 0.7)
					(thickness 0.15)
				)
				(justify left bottom mirror)
			)
		)
		(pad "1" smd roundrect
			(at -0.127 0)
			(size 0.127 0.127)
			(layers "B.Cu")
			(roundrect_rratio 0.5)
			(chamfer_ratio 0)
			(chamfer top_left bottom_left)
			(net 160 "Net-(U30-OUT)")
			(pinfunction "1")
			(pintype "passive")
		)
		(pad "2" smd roundrect
			(at 0.126 0 180)
			(size 0.127 0.127)
			(layers "B.Cu")
			(roundrect_rratio 0.5)
			(chamfer_ratio 0)
			(chamfer top_left bottom_left)
			(net 599 "/FPGA Config/VREFP")
			(pinfunction "2")
			(pintype "passive")
		)
	)
	(footprint "antmicro-footprints:C_0402_1005Metric"
		(layer "B.Cu")
		(at 146.464499 164.653 90)
		(descr "Capacitor SMD 0402")
		(tags "capacitor SMD 0402")
		(property "Reference" "C235"
			(at 1.331 0.347501 90)
			(layer "B.SilkS")
			(effects
				(font
					(size 0.7 0.7)
					(thickness 0.15)
				)
				(justify right bottom mirror)
			)
		)
		(property "Value" "C_100n_0402"
			(at -1.022927 -2.155213 90)
			(layer "B.Fab")
			(effects
				(font
					(size 0.7 0.7)
					(thickness 0.15)
				)
				(justify right bottom mirror)
			)
		)
		(property "Datasheet" "https://www.murata.com/products/productdetail?partno=GRM155R61H104KE14%23"
			(at 0 0 90)
			(layer "F.Fab")
			(hide yes)
			(effects
				(font
					(size 1.27 1.27)
					(thickness 0.15)
				)
			)
		)
		(property "MPN" "GRM155R61H104KE14D"
			(at 0 0 90)
			(unlocked yes)
			(layer "B.Fab")
			(hide yes)
			(effects
				(font
					(size 1 1)
					(thickness 0.15)
				)
				(justify mirror)
			)
		)
		(property "Manufacturer" "Murata"
			(at 0 0 90)
			(unlocked yes)
			(layer "B.Fab")
			(hide yes)
			(effects
				(font
					(size 1 1)
					(thickness 0.15)
				)
				(justify mirror)
			)
		)
		(property "License" "Apache-2.0"
			(at 0 0 90)
			(unlocked yes)
			(layer "B.Fab")
			(hide yes)
			(effects
				(font
					(size 1 1)
					(thickness 0.15)
				)
				(justify mirror)
			)
		)
		(property "Author" "Antmicro"
			(at 0 0 90)
			(unlocked yes)
			(layer "B.Fab")
			(hide yes)
			(effects
				(font
					(size 1 1)
					(thickness 0.15)
				)
				(justify mirror)
			)
		)
		(property "Val" "100n"
			(at 0 0 90)
			(unlocked yes)
			(layer "B.Fab")
			(hide yes)
			(effects
				(font
					(size 1 1)
					(thickness 0.15)
				)
				(justify mirror)
			)
		)
		(property "Voltage" "50V"
			(at 0 0 90)
			(unlocked yes)
			(layer "B.Fab")
			(hide yes)
			(effects
				(font
					(size 1 1)
					(thickness 0.15)
				)
				(justify mirror)
			)
		)
		(property "Dielectric" "X5R"
			(at 0 0 90)
			(unlocked yes)
			(layer "B.Fab")
			(hide yes)
			(effects
				(font
					(size 1 1)
					(thickness 0.15)
				)
				(justify mirror)
			)
		)
		(sheetname "/Debug FTDI + VNA/")
		(sheetfile "debug-ftdi.kicad_sch")
		(attr smd)
		(fp_rect
			(start -0.925 0.47)
			(end 0.925 -0.47)
			(stroke
				(width 0.05)
				(type default)
			)
			(fill no)
			(layer "B.CrtYd")
		)
		(fp_line
			(start 0.504 -0.248)
			(end -0.494 -0.248)
			(stroke
				(width 0.15)
				(type solid)
			)
			(layer "B.Fab")
		)
		(fp_line
			(start -0.494 -0.248)
			(end -0.494 0.25)
			(stroke
				(width 0.15)
				(type solid)
			)
			(layer "B.Fab")
		)
		(fp_line
			(start 0.504 0.25)
			(end 0.504 -0.248)
			(stroke
				(width 0.15)
				(type solid)
			)
			(layer "B.Fab")
		)
		(fp_line
			(start -0.494 0.25)
			(end 0.504 0.25)
			(stroke
				(width 0.15)
				(type solid)
			)
			(layer "B.Fab")
		)
		(fp_text user "${REFERENCE}"
			(at -0.939 -4.599 270)
			(layer "B.Fab")
			(effects
				(font
					(size 0.7 0.7)
					(thickness 0.15)
				)
				(justify left bottom mirror)
			)
		)
		(fp_text user "License: Apache-2.0"
			(at -0.939 -5.799 270)
			(layer "B.Fab")
			(effects
				(font
					(size 0.7 0.7)
					(thickness 0.15)
				)
				(justify left bottom mirror)
			)
		)
		(fp_text user "Author: Antmicro"
			(at -0.939 -3.399 270)
			(layer "B.Fab")
			(effects
				(font
					(size 0.7 0.7)
					(thickness 0.15)
				)
				(justify left bottom mirror)
			)
		)
		(pad "1" smd roundrect
			(at -0.48 0 90)
			(size 0.59 0.64)
			(layers "B.Cu" "B.Mask" "B.Paste")
			(roundrect_rratio 0.25)
			(net 1 "GND")
			(pintype "passive")
		)
		(pad "2" smd roundrect
			(at 0.48 0 90)
			(size 0.59 0.64)
			(layers "B.Cu" "B.Mask" "B.Paste")
			(roundrect_rratio 0.25)
			(net 6 "/Debug FTDI + VNA/FTDI_3V3")
			(pintype "passive")
		)
	)
	(footprint "antmicro-footprints:C_0402_1005Metric_EIA"
		(layer "B.Cu")
		(at 184 162.502 -90)
		(descr "Capacitor SMD 0402 (1005 Metric), square (rectangular) end terminal, IPC_7351 nominal, (Body size source: IPC-SM-782 page 76, https://www.pcb-3d.com/wordpress/wp-content/uploads/ipc-sm-782a_amendment_1_and_2.pdf)")
		(tags "capacitor 0402")
		(property "Reference" "C72"
			(at 1.098 -0.2 90)
			(layer "B.SilkS")
			(effects
				(font
					(size 0.7 0.7)
					(thickness 0.15)
				)
				(justify left bottom mirror)
			)
		)
		(property "Value" "C_4u7_0402"
			(at 0 -1.169 90)
			(layer "B.Fab")
			(effects
				(font
					(size 0.7 0.7)
					(thickness 0.15)
				)
				(justify left bottom mirror)
			)
		)
		(property "Datasheet" "https://www.murata.com/products/productdetail?partno=GRM155R61A475MEAA%23"
			(at 0 0 270)
			(layer "F.Fab")
			(hide yes)
			(effects
				(font
					(size 1.27 1.27)
					(thickness 0.15)
				)
			)
		)
		(property "Manufacturer" "Murata"
			(at 0 0 270)
			(unlocked yes)
			(layer "B.Fab")
			(hide yes)
			(effects
				(font
					(size 1 1)
					(thickness 0.15)
				)
				(justify mirror)
			)
		)
		(property "MPN" "GRM155R61A475MEAAD"
			(at 0 0 270)
			(unlocked yes)
			(layer "B.Fab")
			(hide yes)
			(effects
				(font
					(size 1 1)
					(thickness 0.15)
				)
				(justify mirror)
			)
		)
		(property "Val" "4u7"
			(at 0 0 270)
			(unlocked yes)
			(layer "B.Fab")
			(hide yes)
			(effects
				(font
					(size 1 1)
					(thickness 0.15)
				)
				(justify mirror)
			)
		)
		(property "License" "Apache-2.0"
			(at 0 0 270)
			(unlocked yes)
			(layer "B.Fab")
			(hide yes)
			(effects
				(font
					(size 1 1)
					(thickness 0.15)
				)
				(justify mirror)
			)
		)
		(property "Author" "Antmicro"
			(at 0 0 270)
			(unlocked yes)
			(layer "B.Fab")
			(hide yes)
			(effects
				(font
					(size 1 1)
					(thickness 0.15)
				)
				(justify mirror)
			)
		)
		(property "Voltage" ""
			(at 0 0 270)
			(unlocked yes)
			(layer "B.Fab")
			(hide yes)
			(effects
				(font
					(size 1 1)
					(thickness 0.15)
				)
				(justify mirror)
			)
		)
		(property "Dielectric" ""
			(at 0 0 270)
			(unlocked yes)
			(layer "B.Fab")
			(hide yes)
			(effects
				(font
					(size 1 1)
					(thickness 0.15)
				)
				(justify mirror)
			)
		)
		(sheetname "/FPGA power/")
		(sheetfile "fpga-power.kicad_sch")
		(attr smd)
		(fp_rect
			(start -0.95 0.45)
			(end 0.95 -0.45)
			(stroke
				(width 0.05)
				(type default)
			)
			(fill no)
			(layer "B.CrtYd")
		)
		(fp_line
			(start -0.5 0.25)
			(end 0.498 0.25)
			(stroke
				(width 0.15)
				(type solid)
			)
			(layer "B.Fab")
		)
		(fp_line
			(start 0.498 0.25)
			(end 0.498 -0.248)
			(stroke
				(width 0.15)
				(type solid)
			)
			(layer "B.Fab")
		)
		(fp_line
			(start -0.5 -0.248)
			(end -0.5 0.25)
			(stroke
				(width 0.15)
				(type solid)
			)
			(layer "B.Fab")
		)
		(fp_line
			(start 0.498 -0.248)
			(end -0.5 -0.248)
			(stroke
				(width 0.15)
				(type solid)
			)
			(layer "B.Fab")
		)
		(fp_text user "License: Apache-2.0"
			(at -0.9656 -4.369 90)
			(layer "B.Fab")
			(effects
				(font
					(size 0.7 0.7)
					(thickness 0.15)
				)
				(justify left bottom mirror)
			)
		)
		(fp_text user "Author: Antmicro"
			(at -0.9656 -5.569 90)
			(layer "B.Fab")
			(effects
				(font
					(size 0.7 0.7)
					(thickness 0.15)
				)
				(justify left bottom mirror)
			)
		)
		(fp_text user "${REFERENCE}"
			(at -0.9656 -3.169 90)
			(layer "B.Fab")
			(effects
				(font
					(size 0.7 0.7)
					(thickness 0.15)
				)
				(justify left bottom mirror)
			)
		)
		(pad "1" smd roundrect
			(at -0.5 0 180)
			(size 0.6 0.6)
			(layers "B.Cu" "B.Mask" "B.Paste")
			(roundrect_rratio 0.25)
			(net 172 "+1V2_MGTAVTT")
			(pintype "passive")
		)
		(pad "2" smd roundrect
			(at 0.498 0 270)
			(size 0.6 0.6)
			(layers "B.Cu" "B.Mask" "B.Paste")
			(roundrect_rratio 0.25)
			(net 1 "GND")
			(pintype "passive")
		)
	)
)
